(kicad_pcb
	(version 20260206)
	(generator "pcbnew")
	(generator_version "10.0")
	(general
		(thickness 1.6)
		(legacy_teardrops no)
	)
	(paper "A4")
	(title_block
		(title "01162023_DA0F0TEBIF0_F0T_Expander_BD_F_brd_V02_OCP.brd")
		(comment 1 "Grand Teton / footprints 4779-4785 of 9728")
	)
	(layers
		(0 "F.Cu" signal "TOP")
		(4 "In1.Cu" signal "GND")
		(6 "In2.Cu" signal "VCC")
		(8 "In3.Cu" signal "VCC1")
		(10 "In4.Cu" signal "GND1")
		(12 "In5.Cu" signal "IN1")
		(14 "In6.Cu" signal "GND2")
		(16 "In7.Cu" signal "IN2")
		(18 "In8.Cu" signal "GND3")
		(20 "In9.Cu" signal "IN3")
		(22 "In10.Cu" signal "GND4")
		(24 "In11.Cu" signal "IN4")
		(26 "In12.Cu" signal "GND5")
		(28 "In13.Cu" signal "IN5")
		(30 "In14.Cu" signal "GND6")
		(32 "In15.Cu" signal "IN6")
		(34 "In16.Cu" signal "GND7")
		(2 "B.Cu" signal "BOTTOM")
		(9 "F.Adhes" user "F.Adhesive")
		(11 "B.Adhes" user "B.Adhesive")
		(13 "F.Paste" user "Package Geometry/Pastemask Top")
		(15 "B.Paste" user "Package Geometry/Pastemask Bottom")
		(5 "F.SilkS" user "Ref Des/Silkscreen Top")
		(7 "B.SilkS" user "Ref Des/Silkscreen Bottom")
		(1 "F.Mask" user "Board Geometry/Soldermask Top")
		(3 "B.Mask" user "Board Geometry/Soldermask Bottom")
		(17 "Dwgs.User" user "User.Drawings")
		(19 "Cmts.User" user "User.Comments")
		(21 "Eco1.User" user "User.Eco1")
		(23 "Eco2.User" user "User.Eco2")
		(25 "Edge.Cuts" user "Board Geometry/Outline")
		(27 "Margin" user)
		(31 "F.CrtYd" user "Package Geometry/Place Bound Top")
		(29 "B.CrtYd" user "Package Geometry/Place Bound Bottom")
		(35 "F.Fab" user "Ref Des/Assembly Top")
		(33 "B.Fab" user "Ref Des/Assembly Bottom")
	)
	(footprint ""
		(layer "F.Cu")
		(at 203.294996 -59.577986 90)
		(property "Reference" "PC542"
			(at 0 0 90)
			(layer "F.SilkS")
			(hide yes)
			(effects
				(font
					(size 1.27 1.27)
				)
			)
		)
		(property "Value" ""
			(at 0 0 90)
			(layer "F.Fab")
			(effects
				(font
					(size 1.27 1.27)
				)
			)
		)
		(duplicate_pad_numbers_are_jumpers no)
		(fp_line
			(start 0.7874 -0.4064)
			(end 0.7874 0.4064)
			(stroke
				(width 0.1524)
				(type default)
			)
			(layer "F.SilkS")
		)
		(fp_line
			(start -0.7874 -0.4064)
			(end 0.7874 -0.4064)
			(stroke
				(width 0.1524)
				(type default)
			)
			(layer "F.SilkS")
		)
		(fp_line
			(start 0.7874 0.4064)
			(end -0.7874 0.4064)
			(stroke
				(width 0.1524)
				(type default)
			)
			(layer "F.SilkS")
		)
		(fp_line
			(start -0.7874 0.4064)
			(end -0.7874 -0.4064)
			(stroke
				(width 0.1524)
				(type default)
			)
			(layer "F.SilkS")
		)
		(fp_line
			(start -0.12065 -0.305054)
			(end -0.12065 -0.2794)
			(stroke
				(width 0.1)
				(type default)
			)
			(layer "F.Fab")
		)
		(fp_line
			(start -0.67945 -0.305054)
			(end -0.12065 -0.305054)
			(stroke
				(width 0.1)
				(type default)
			)
			(layer "F.Fab")
		)
		(fp_line
			(start 0.67945 -0.3048)
			(end 0.67945 0.3048)
			(stroke
				(width 0.1)
				(type default)
			)
			(layer "F.Fab")
		)
		(fp_line
			(start 0.12065 -0.3048)
			(end 0.67945 -0.3048)
			(stroke
				(width 0.1)
				(type default)
			)
			(layer "F.Fab")
		)
		(fp_line
			(start 0.12065 -0.2794)
			(end 0.12065 -0.3048)
			(stroke
				(width 0.1)
				(type default)
			)
			(layer "F.Fab")
		)
		(fp_line
			(start -0.12065 -0.2794)
			(end 0.12065 -0.2794)
			(stroke
				(width 0.1)
				(type default)
			)
			(layer "F.Fab")
		)
		(fp_line
			(start 0.120396 0.2794)
			(end -0.12065 0.2794)
			(stroke
				(width 0.1)
				(type default)
			)
			(layer "F.Fab")
		)
		(fp_line
			(start -0.12065 0.2794)
			(end -0.12065 0.3048)
			(stroke
				(width 0.1)
				(type default)
			)
			(layer "F.Fab")
		)
		(fp_line
			(start 0.67945 0.3048)
			(end 0.120396 0.3048)
			(stroke
				(width 0.1)
				(type default)
			)
			(layer "F.Fab")
		)
		(fp_line
			(start 0.120396 0.3048)
			(end 0.120396 0.2794)
			(stroke
				(width 0.1)
				(type default)
			)
			(layer "F.Fab")
		)
		(fp_line
			(start -0.12065 0.3048)
			(end -0.67945 0.3048)
			(stroke
				(width 0.1)
				(type default)
			)
			(layer "F.Fab")
		)
		(fp_line
			(start -0.67945 0.3048)
			(end -0.67945 -0.305054)
			(stroke
				(width 0.1)
				(type default)
			)
			(layer "F.Fab")
		)
		(pad "1" smd circle
			(at -0.40005 0 90)
			(size 0 0)
			(layers "F.Cu" "F.Mask" "F.Paste")
			(net "P3V3_SSD7_SS")
		)
		(pad "2" smd circle
			(at 0.40005 0 90)
			(size 0 0)
			(layers "F.Cu" "F.Mask" "F.Paste")
			(net "GND")
		)
	)
	(footprint ""
		(layer "F.Cu")
		(at 376.051572 -260.840982)
		(property "Reference" "R4597"
			(at 0 0 0)
			(layer "F.SilkS")
			(hide yes)
			(effects
				(font
					(size 1.27 1.27)
				)
			)
		)
		(property "Value" ""
			(at 0 0 0)
			(layer "F.Fab")
			(effects
				(font
					(size 1.27 1.27)
				)
			)
		)
		(duplicate_pad_numbers_are_jumpers no)
		(fp_line
			(start -0.7874 -0.4064)
			(end 0.7874 -0.4064)
			(stroke
				(width 0.1524)
				(type default)
			)
			(layer "F.SilkS")
		)
		(fp_line
			(start -0.7874 0.4064)
			(end -0.7874 -0.4064)
			(stroke
				(width 0.1524)
				(type default)
			)
			(layer "F.SilkS")
		)
		(fp_line
			(start 0.7874 -0.4064)
			(end 0.7874 0.4064)
			(stroke
				(width 0.1524)
				(type default)
			)
			(layer "F.SilkS")
		)
		(fp_line
			(start 0.7874 0.4064)
			(end -0.7874 0.4064)
			(stroke
				(width 0.1524)
				(type default)
			)
			(layer "F.SilkS")
		)
		(fp_line
			(start -0.67945 -0.305054)
			(end -0.12065 -0.305054)
			(stroke
				(width 0.1)
				(type default)
			)
			(layer "F.Fab")
		)
		(fp_line
			(start -0.67945 0.3048)
			(end -0.67945 -0.305054)
			(stroke
				(width 0.1)
				(type default)
			)
			(layer "F.Fab")
		)
		(fp_line
			(start -0.12065 -0.305054)
			(end -0.12065 -0.2794)
			(stroke
				(width 0.1)
				(type default)
			)
			(layer "F.Fab")
		)
		(fp_line
			(start -0.12065 -0.2794)
			(end 0.12065 -0.2794)
			(stroke
				(width 0.1)
				(type default)
			)
			(layer "F.Fab")
		)
		(fp_line
			(start -0.12065 0.2794)
			(end -0.12065 0.3048)
			(stroke
				(width 0.1)
				(type default)
			)
			(layer "F.Fab")
		)
		(fp_line
			(start -0.12065 0.3048)
			(end -0.67945 0.3048)
			(stroke
				(width 0.1)
				(type default)
			)
			(layer "F.Fab")
		)
		(fp_line
			(start 0.120396 0.2794)
			(end -0.12065 0.2794)
			(stroke
				(width 0.1)
				(type default)
			)
			(layer "F.Fab")
		)
		(fp_line
			(start 0.120396 0.3048)
			(end 0.120396 0.2794)
			(stroke
				(width 0.1)
				(type default)
			)
			(layer "F.Fab")
		)
		(fp_line
			(start 0.12065 -0.3048)
			(end 0.67945 -0.3048)
			(stroke
				(width 0.1)
				(type default)
			)
			(layer "F.Fab")
		)
		(fp_line
			(start 0.12065 -0.2794)
			(end 0.12065 -0.3048)
			(stroke
				(width 0.1)
				(type default)
			)
			(layer "F.Fab")
		)
		(fp_line
			(start 0.67945 -0.3048)
			(end 0.67945 0.3048)
			(stroke
				(width 0.1)
				(type default)
			)
			(layer "F.Fab")
		)
		(fp_line
			(start 0.67945 0.3048)
			(end 0.120396 0.3048)
			(stroke
				(width 0.1)
				(type default)
			)
			(layer "F.Fab")
		)
		(pad "1" smd circle
			(at -0.40005 0)
			(size 0 0)
			(layers "F.Cu" "F.Mask" "F.Paste")
			(net "P1V8_VDDA_PEX3")
		)
		(pad "2" smd circle
			(at 0.40005 0)
			(size 0 0)
			(layers "F.Cu" "F.Mask" "F.Paste")
			(net "P1V8_VDDA_PEX3_R")
		)
	)
	(footprint ""
		(layer "F.Cu")
		(at 80.019398 -119.584724 180)
		(property "Reference" "C31"
			(at 0 0 180)
			(layer "F.SilkS")
			(hide yes)
			(effects
				(font
					(size 1.27 1.27)
				)
			)
		)
		(property "Value" ""
			(at 0 0 180)
			(layer "F.Fab")
			(effects
				(font
					(size 1.27 1.27)
				)
			)
		)
		(duplicate_pad_numbers_are_jumpers no)
		(fp_line
			(start 0.299974 0.150114)
			(end -0.299974 0.150114)
			(stroke
				(width 0.1)
				(type default)
			)
			(layer "F.Fab")
		)
		(fp_line
			(start 0.299974 -0.150114)
			(end 0.299974 0.150114)
			(stroke
				(width 0.1)
				(type default)
			)
			(layer "F.Fab")
		)
		(fp_line
			(start -0.299974 0.150114)
			(end -0.299974 -0.150114)
			(stroke
				(width 0.1)
				(type default)
			)
			(layer "F.Fab")
		)
		(fp_line
			(start -0.299974 -0.150114)
			(end 0.299974 -0.150114)
			(stroke
				(width 0.1)
				(type default)
			)
			(layer "F.Fab")
		)
		(pad "1" smd rect
			(at -0.2667 0 180)
			(size 0.3048 0.381)
			(layers "F.Cu" "F.Mask" "F.Paste")
			(net "P5E_PEX0_STN0_TX_DP<0>")
		)
		(pad "2" smd rect
			(at 0.2667 0 180)
			(size 0.3048 0.381)
			(layers "F.Cu" "F.Mask" "F.Paste")
			(net "P5E_PEX0_STN0_TX_C_DP<0>")
		)
	)
	(footprint ""
		(layer "F.Cu")
		(at 400.567906 -55.083456)
		(property "Reference" "PC445"
			(at 0 0 0)
			(layer "F.SilkS")
			(hide yes)
			(effects
				(font
					(size 1.27 1.27)
				)
			)
		)
		(property "Value" ""
			(at 0 0 0)
			(layer "F.Fab")
			(effects
				(font
					(size 1.27 1.27)
				)
			)
		)
		(duplicate_pad_numbers_are_jumpers no)
		(fp_line
			(start -0.7874 -0.4064)
			(end 0.7874 -0.4064)
			(stroke
				(width 0.1524)
				(type default)
			)
			(layer "F.SilkS")
		)
		(fp_line
			(start -0.7874 0.4064)
			(end -0.7874 -0.4064)
			(stroke
				(width 0.1524)
				(type default)
			)
			(layer "F.SilkS")
		)
		(fp_line
			(start 0.7874 -0.4064)
			(end 0.7874 0.4064)
			(stroke
				(width 0.1524)
				(type default)
			)
			(layer "F.SilkS")
		)
		(fp_line
			(start 0.7874 0.4064)
			(end -0.7874 0.4064)
			(stroke
				(width 0.1524)
				(type default)
			)
			(layer "F.SilkS")
		)
		(fp_line
			(start -0.67945 -0.305054)
			(end -0.12065 -0.305054)
			(stroke
				(width 0.1)
				(type default)
			)
			(layer "F.Fab")
		)
		(fp_line
			(start -0.67945 0.3048)
			(end -0.67945 -0.305054)
			(stroke
				(width 0.1)
				(type default)
			)
			(layer "F.Fab")
		)
		(fp_line
			(start -0.12065 -0.305054)
			(end -0.12065 -0.2794)
			(stroke
				(width 0.1)
				(type default)
			)
			(layer "F.Fab")
		)
		(fp_line
			(start -0.12065 -0.2794)
			(end 0.12065 -0.2794)
			(stroke
				(width 0.1)
				(type default)
			)
			(layer "F.Fab")
		)
		(fp_line
			(start -0.12065 0.2794)
			(end -0.12065 0.3048)
			(stroke
				(width 0.1)
				(type default)
			)
			(layer "F.Fab")
		)
		(fp_line
			(start -0.12065 0.3048)
			(end -0.67945 0.3048)
			(stroke
				(width 0.1)
				(type default)
			)
			(layer "F.Fab")
		)
		(fp_line
			(start 0.120396 0.2794)
			(end -0.12065 0.2794)
			(stroke
				(width 0.1)
				(type default)
			)
			(layer "F.Fab")
		)
		(fp_line
			(start 0.120396 0.3048)
			(end 0.120396 0.2794)
			(stroke
				(width 0.1)
				(type default)
			)
			(layer "F.Fab")
		)
		(fp_line
			(start 0.12065 -0.3048)
			(end 0.67945 -0.3048)
			(stroke
				(width 0.1)
				(type default)
			)
			(layer "F.Fab")
		)
		(fp_line
			(start 0.12065 -0.2794)
			(end 0.12065 -0.3048)
			(stroke
				(width 0.1)
				(type default)
			)
			(layer "F.Fab")
		)
		(fp_line
			(start 0.67945 -0.3048)
			(end 0.67945 0.3048)
			(stroke
				(width 0.1)
				(type default)
			)
			(layer "F.Fab")
		)
		(fp_line
			(start 0.67945 0.3048)
			(end 0.120396 0.3048)
			(stroke
				(width 0.1)
				(type default)
			)
			(layer "F.Fab")
		)
		(pad "1" smd circle
			(at -0.40005 0)
			(size 0 0)
			(layers "F.Cu" "F.Mask" "F.Paste")
			(net "P5V_AUX")
		)
		(pad "2" smd circle
			(at 0.40005 0)
			(size 0 0)
			(layers "F.Cu" "F.Mask" "F.Paste")
			(net "GND")
		)
	)
	(footprint ""
		(layer "F.Cu")
		(at 452.567802 -54.067456)
		(property "Reference" "PR238"
			(at 0 0 0)
			(layer "F.SilkS")
			(hide yes)
			(effects
				(font
					(size 1.27 1.27)
				)
			)
		)
		(property "Value" ""
			(at 0 0 0)
			(layer "F.Fab")
			(effects
				(font
					(size 1.27 1.27)
				)
			)
		)
		(duplicate_pad_numbers_are_jumpers no)
		(fp_line
			(start -0.7874 -0.4064)
			(end 0.7874 -0.4064)
			(stroke
				(width 0.1524)
				(type default)
			)
			(layer "F.SilkS")
		)
		(fp_line
			(start -0.7874 0.4064)
			(end -0.7874 -0.4064)
			(stroke
				(width 0.1524)
				(type default)
			)
			(layer "F.SilkS")
		)
		(fp_line
			(start 0.7874 -0.4064)
			(end 0.7874 0.4064)
			(stroke
				(width 0.1524)
				(type default)
			)
			(layer "F.SilkS")
		)
		(fp_line
			(start 0.7874 0.4064)
			(end -0.7874 0.4064)
			(stroke
				(width 0.1524)
				(type default)
			)
			(layer "F.SilkS")
		)
		(fp_line
			(start -0.67945 -0.305054)
			(end -0.12065 -0.305054)
			(stroke
				(width 0.1)
				(type default)
			)
			(layer "F.Fab")
		)
		(fp_line
			(start -0.67945 0.3048)
			(end -0.67945 -0.305054)
			(stroke
				(width 0.1)
				(type default)
			)
			(layer "F.Fab")
		)
		(fp_line
			(start -0.12065 -0.305054)
			(end -0.12065 -0.2794)
			(stroke
				(width 0.1)
				(type default)
			)
			(layer "F.Fab")
		)
		(fp_line
			(start -0.12065 -0.2794)
			(end 0.12065 -0.2794)
			(stroke
				(width 0.1)
				(type default)
			)
			(layer "F.Fab")
		)
		(fp_line
			(start -0.12065 0.2794)
			(end -0.12065 0.3048)
			(stroke
				(width 0.1)
				(type default)
			)
			(layer "F.Fab")
		)
		(fp_line
			(start -0.12065 0.3048)
			(end -0.67945 0.3048)
			(stroke
				(width 0.1)
				(type default)
			)
			(layer "F.Fab")
		)
		(fp_line
			(start 0.120396 0.2794)
			(end -0.12065 0.2794)
			(stroke
				(width 0.1)
				(type default)
			)
			(layer "F.Fab")
		)
		(fp_line
			(start 0.120396 0.3048)
			(end 0.120396 0.2794)
			(stroke
				(width 0.1)
				(type default)
			)
			(layer "F.Fab")
		)
		(fp_line
			(start 0.12065 -0.3048)
			(end 0.67945 -0.3048)
			(stroke
				(width 0.1)
				(type default)
			)
			(layer "F.Fab")
		)
		(fp_line
			(start 0.12065 -0.2794)
			(end 0.12065 -0.3048)
			(stroke
				(width 0.1)
				(type default)
			)
			(layer "F.Fab")
		)
		(fp_line
			(start 0.67945 -0.3048)
			(end 0.67945 0.3048)
			(stroke
				(width 0.1)
				(type default)
			)
			(layer "F.Fab")
		)
		(fp_line
			(start 0.67945 0.3048)
			(end 0.120396 0.3048)
			(stroke
				(width 0.1)
				(type default)
			)
			(layer "F.Fab")
		)
		(pad "1" smd circle
			(at -0.40005 0)
			(size 0 0)
			(layers "F.Cu" "F.Mask" "F.Paste")
			(net "P12V_SSD15_OCP")
		)
		(pad "2" smd circle
			(at 0.40005 0)
			(size 0 0)
			(layers "F.Cu" "F.Mask" "F.Paste")
			(net "GND")
		)
	)
	(footprint ""
		(layer "F.Cu")
		(at 317.30442 -302.493934 -90)
		(property "Reference" "R6810"
			(at 0 0 270)
			(layer "F.SilkS")
			(hide yes)
			(effects
				(font
					(size 1.27 1.27)
				)
			)
		)
		(property "Value" ""
			(at 0 0 270)
			(layer "F.Fab")
			(effects
				(font
					(size 1.27 1.27)
				)
			)
		)
		(duplicate_pad_numbers_are_jumpers no)
		(fp_line
			(start -0.7874 0.4064)
			(end -0.7874 -0.4064)
			(stroke
				(width 0.1524)
				(type default)
			)
			(layer "F.SilkS")
		)
		(fp_line
			(start 0.7874 0.4064)
			(end -0.7874 0.4064)
			(stroke
				(width 0.1524)
				(type default)
			)
			(layer "F.SilkS")
		)
		(fp_line
			(start -0.7874 -0.4064)
			(end 0.7874 -0.4064)
			(stroke
				(width 0.1524)
				(type default)
			)
			(layer "F.SilkS")
		)
		(fp_line
			(start 0.7874 -0.4064)
			(end 0.7874 0.4064)
			(stroke
				(width 0.1524)
				(type default)
			)
			(layer "F.SilkS")
		)
		(fp_line
			(start -0.67945 0.3048)
			(end -0.67945 -0.305054)
			(stroke
				(width 0.1)
				(type default)
			)
			(layer "F.Fab")
		)
		(fp_line
			(start -0.12065 0.3048)
			(end -0.67945 0.3048)
			(stroke
				(width 0.1)
				(type default)
			)
			(layer "F.Fab")
		)
		(fp_line
			(start 0.120396 0.3048)
			(end 0.120396 0.2794)
			(stroke
				(width 0.1)
				(type default)
			)
			(layer "F.Fab")
		)
		(fp_line
			(start 0.67945 0.3048)
			(end 0.120396 0.3048)
			(stroke
				(width 0.1)
				(type default)
			)
			(layer "F.Fab")
		)
		(fp_line
			(start -0.12065 0.2794)
			(end -0.12065 0.3048)
			(stroke
				(width 0.1)
				(type default)
			)
			(layer "F.Fab")
		)
		(fp_line
			(start 0.120396 0.2794)
			(end -0.12065 0.2794)
			(stroke
				(width 0.1)
				(type default)
			)
			(layer "F.Fab")
		)
		(fp_line
			(start -0.12065 -0.2794)
			(end 0.12065 -0.2794)
			(stroke
				(width 0.1)
				(type default)
			)
			(layer "F.Fab")
		)
		(fp_line
			(start 0.12065 -0.2794)
			(end 0.12065 -0.3048)
			(stroke
				(width 0.1)
				(type default)
			)
			(layer "F.Fab")
		)
		(fp_line
			(start 0.12065 -0.3048)
			(end 0.67945 -0.3048)
			(stroke
				(width 0.1)
				(type default)
			)
			(layer "F.Fab")
		)
		(fp_line
			(start 0.67945 -0.3048)
			(end 0.67945 0.3048)
			(stroke
				(width 0.1)
				(type default)
			)
			(layer "F.Fab")
		)
		(fp_line
			(start -0.67945 -0.305054)
			(end -0.12065 -0.305054)
			(stroke
				(width 0.1)
				(type default)
			)
			(layer "F.Fab")
		)
		(fp_line
			(start -0.12065 -0.305054)
			(end -0.12065 -0.2794)
			(stroke
				(width 0.1)
				(type default)
			)
			(layer "F.Fab")
		)
		(pad "1" smd circle
			(at -0.40005 0 270)
			(size 0 0)
			(layers "F.Cu" "F.Mask" "F.Paste")
			(net "SMB_PEX2_R_SCL")
		)
		(pad "2" smd circle
			(at 0.40005 0 270)
			(size 0 0)
			(layers "F.Cu" "F.Mask" "F.Paste")
			(net "SMB_PEX2_SCL")
		)
	)
	(footprint ""
		(layer "F.Cu")
		(at 92.899992 -289.230816 -90)
		(property "Reference" "R3877"
			(at 0 0 270)
			(layer "F.SilkS")
			(hide yes)
			(effects
				(font
					(size 1.27 1.27)
				)
			)
		)
		(property "Value" ""
			(at 0 0 270)
			(layer "F.Fab")
			(effects
				(font
					(size 1.27 1.27)
				)
			)
		)
		(duplicate_pad_numbers_are_jumpers no)
		(fp_line
			(start -0.7874 0.4064)
			(end -0.7874 -0.4064)
			(stroke
				(width 0.1524)
				(type default)
			)
			(layer "F.SilkS")
		)
		(fp_line
			(start 0.7874 0.4064)
			(end -0.7874 0.4064)
			(stroke
				(width 0.1524)
				(type default)
			)
			(layer "F.SilkS")
		)
		(fp_line
			(start -0.7874 -0.4064)
			(end 0.7874 -0.4064)
			(stroke
				(width 0.1524)
				(type default)
			)
			(layer "F.SilkS")
		)
		(fp_line
			(start 0.7874 -0.4064)
			(end 0.7874 0.4064)
			(stroke
				(width 0.1524)
				(type default)
			)
			(layer "F.SilkS")
		)
		(fp_line
			(start -0.67945 0.3048)
			(end -0.67945 -0.305054)
			(stroke
				(width 0.1)
				(type default)
			)
			(layer "F.Fab")
		)
		(fp_line
			(start -0.12065 0.3048)
			(end -0.67945 0.3048)
			(stroke
				(width 0.1)
				(type default)
			)
			(layer "F.Fab")
		)
		(fp_line
			(start 0.120396 0.3048)
			(end 0.120396 0.2794)
			(stroke
				(width 0.1)
				(type default)
			)
			(layer "F.Fab")
		)
		(fp_line
			(start 0.67945 0.3048)
			(end 0.120396 0.3048)
			(stroke
				(width 0.1)
				(type default)
			)
			(layer "F.Fab")
		)
		(fp_line
			(start -0.12065 0.2794)
			(end -0.12065 0.3048)
			(stroke
				(width 0.1)
				(type default)
			)
			(layer "F.Fab")
		)
		(fp_line
			(start 0.120396 0.2794)
			(end -0.12065 0.2794)
			(stroke
				(width 0.1)
				(type default)
			)
			(layer "F.Fab")
		)
		(fp_line
			(start -0.12065 -0.2794)
			(end 0.12065 -0.2794)
			(stroke
				(width 0.1)
				(type default)
			)
			(layer "F.Fab")
		)
		(fp_line
			(start 0.12065 -0.2794)
			(end 0.12065 -0.3048)
			(stroke
				(width 0.1)
				(type default)
			)
			(layer "F.Fab")
		)
		(fp_line
			(start 0.12065 -0.3048)
			(end 0.67945 -0.3048)
			(stroke
				(width 0.1)
				(type default)
			)
			(layer "F.Fab")
		)
		(fp_line
			(start 0.67945 -0.3048)
			(end 0.67945 0.3048)
			(stroke
				(width 0.1)
				(type default)
			)
			(layer "F.Fab")
		)
		(fp_line
			(start -0.67945 -0.305054)
			(end -0.12065 -0.305054)
			(stroke
				(width 0.1)
				(type default)
			)
			(layer "F.Fab")
		)
		(fp_line
			(start -0.12065 -0.305054)
			(end -0.12065 -0.2794)
			(stroke
				(width 0.1)
				(type default)
			)
			(layer "F.Fab")
		)
		(pad "1" smd circle
			(at -0.40005 0 270)
			(size 0 0)
			(layers "F.Cu" "F.Mask" "F.Paste")
			(net "SMB_PEX0_HOST_LS_SCL")
		)
		(pad "2" smd circle
			(at 0.40005 0 270)
			(size 0 0)
			(layers "F.Cu" "F.Mask" "F.Paste")
			(net "P3V3_AUX")
		)
	)
)
